(kicad_pcb
	(version 20260206)
	(generator "pcbnew")
	(generator_version "10.0")
	(general
		(thickness 1.6)
		(legacy_teardrops no)
	)
	(paper "A4")
	(title_block
		(title "v2-pdb — ms_pdb_v2.brd")
		(comment 1 "Open CloudServer (Microsoft) / footprints 211-220 of 348")
	)
	(layers
		(0 "F.Cu" signal "TOP")
		(4 "In1.Cu" signal "GND")
		(6 "In2.Cu" signal "IN1")
		(8 "In3.Cu" signal "VCC")
		(10 "In4.Cu" signal "VCC1")
		(12 "In5.Cu" signal "IN2")
		(14 "In6.Cu" signal "GND1")
		(2 "B.Cu" signal "BOTTOM")
		(9 "F.Adhes" user "F.Adhesive")
		(11 "B.Adhes" user "B.Adhesive")
		(13 "F.Paste" user "Package Geometry/Pastemask Top")
		(15 "B.Paste" user "Package Geometry/Pastemask Bottom")
		(5 "F.SilkS" user "Ref Des/Silkscreen Top")
		(7 "B.SilkS" user "Ref Des/Silkscreen Bottom")
		(1 "F.Mask" user "Board Geometry/Soldermask Top")
		(3 "B.Mask" user "Board Geometry/Soldermask Bottom")
		(17 "Dwgs.User" user "User.Drawings")
		(19 "Cmts.User" user "User.Comments")
		(21 "Eco1.User" user "User.Eco1")
		(23 "Eco2.User" user "User.Eco2")
		(25 "Edge.Cuts" user "Board Geometry/Outline")
		(27 "Margin" user)
		(31 "F.CrtYd" user "Package Geometry/Place Bound Top")
		(29 "B.CrtYd" user "Package Geometry/Place Bound Bottom")
		(35 "F.Fab" user "Ref Des/Assembly Top")
		(33 "B.Fab" user "Ref Des/Assembly Bottom")
	)
	(footprint ""
		(layer "F.Cu")
		(at 26.125678 -278.486362 180)
		(property "Reference" "R52"
			(at 3.845306 0.107188 0)
			(unlocked yes)
			(layer "F.SilkS")
			(effects
				(font
					(size 0.7874 0.5842)
					(thickness 0.1524)
				)
				(justify left)
			)
		)
		(property "Value" ""
			(at 0 0 180)
			(layer "F.Fab")
			(effects
				(font
					(size 1.27 1.27)
				)
			)
		)
		(duplicate_pad_numbers_are_jumpers no)
		(fp_line
			(start 0.7874 0.4064)
			(end -0.7874 0.4064)
			(stroke
				(width 0.1524)
				(type default)
			)
			(layer "F.SilkS")
		)
		(fp_line
			(start 0.7874 -0.4064)
			(end 0.7874 0.4064)
			(stroke
				(width 0.1524)
				(type default)
			)
			(layer "F.SilkS")
		)
		(fp_line
			(start -0.7874 0.4064)
			(end -0.7874 -0.4064)
			(stroke
				(width 0.1524)
				(type default)
			)
			(layer "F.SilkS")
		)
		(fp_line
			(start -0.7874 -0.4064)
			(end 0.7874 -0.4064)
			(stroke
				(width 0.1524)
				(type default)
			)
			(layer "F.SilkS")
		)
		(fp_poly
			(pts
				(xy -0.508 0.2794) (xy -0.508 0.2286) (xy -0.635 0.2286) (xy -0.635 -0.254) (xy -0.5334 -0.254)
				(xy -0.5334 -0.2794) (xy 0.5334 -0.2794) (xy 0.5334 -0.254) (xy 0.635 -0.254) (xy 0.635 0.254) (xy 0.5334 0.254)
				(xy 0.5334 0.2794)
			)
			(stroke
				(width 0)
				(type default)
			)
			(fill no)
			(layer "F.CrtYd")
		)
		(pad "1" smd rect
			(at 0.40005 0 180)
			(size 0.4572 0.508)
			(layers "F.Cu" "F.Mask" "F.Paste")
			(net "GND")
		)
		(pad "2" smd rect
			(at -0.40005 0 180)
			(size 0.4572 0.508)
			(layers "F.Cu" "F.Mask" "F.Paste")
			(net "PSU4_PS_ON_N")
		)
	)
	(footprint ""
		(layer "F.Cu")
		(at 26.102056 -277.377144)
		(property "Reference" "R56"
			(at -4.060444 0.200152 0)
			(unlocked yes)
			(layer "F.SilkS")
			(effects
				(font
					(size 0.7874 0.5842)
					(thickness 0.1524)
				)
				(justify left)
			)
		)
		(property "Value" ""
			(at 0 0 0)
			(layer "F.Fab")
			(effects
				(font
					(size 1.27 1.27)
				)
			)
		)
		(duplicate_pad_numbers_are_jumpers no)
		(fp_line
			(start -0.7874 -0.4064)
			(end 0.7874 -0.4064)
			(stroke
				(width 0.1524)
				(type default)
			)
			(layer "F.SilkS")
		)
		(fp_line
			(start -0.7874 0.4064)
			(end -0.7874 -0.4064)
			(stroke
				(width 0.1524)
				(type default)
			)
			(layer "F.SilkS")
		)
		(fp_line
			(start 0.7874 -0.4064)
			(end 0.7874 0.4064)
			(stroke
				(width 0.1524)
				(type default)
			)
			(layer "F.SilkS")
		)
		(fp_line
			(start 0.7874 0.4064)
			(end -0.7874 0.4064)
			(stroke
				(width 0.1524)
				(type default)
			)
			(layer "F.SilkS")
		)
		(fp_poly
			(pts
				(xy -0.508 0.2794) (xy -0.508 0.2286) (xy -0.635 0.2286) (xy -0.635 -0.254) (xy -0.5334 -0.254)
				(xy -0.5334 -0.2794) (xy 0.5334 -0.2794) (xy 0.5334 -0.254) (xy 0.635 -0.254) (xy 0.635 0.254) (xy 0.5334 0.254)
				(xy 0.5334 0.2794)
			)
			(stroke
				(width 0)
				(type default)
			)
			(fill no)
			(layer "F.CrtYd")
		)
		(pad "1" smd rect
			(at 0.40005 0)
			(size 0.4572 0.508)
			(layers "F.Cu" "F.Mask" "F.Paste")
			(net "PSU4_PS_KILL")
		)
		(pad "2" smd rect
			(at -0.40005 0)
			(size 0.4572 0.508)
			(layers "F.Cu" "F.Mask" "F.Paste")
			(net "GND")
		)
	)
	(footprint ""
		(layer "F.Cu")
		(at 27.239976 -461.829912)
		(property "Reference" "R22"
			(at -2.45364 -1.05029 0)
			(unlocked yes)
			(layer "F.SilkS")
			(effects
				(font
					(size 0.7874 0.5842)
					(thickness 0.1524)
				)
				(justify left)
			)
		)
		(property "Value" ""
			(at 0 0 0)
			(layer "F.Fab")
			(effects
				(font
					(size 1.27 1.27)
				)
			)
		)
		(duplicate_pad_numbers_are_jumpers no)
		(fp_line
			(start -0.7874 -0.4064)
			(end 0.7874 -0.4064)
			(stroke
				(width 0.1524)
				(type default)
			)
			(layer "F.SilkS")
		)
		(fp_line
			(start -0.7874 0.4064)
			(end -0.7874 -0.4064)
			(stroke
				(width 0.1524)
				(type default)
			)
			(layer "F.SilkS")
		)
		(fp_line
			(start 0.7874 -0.4064)
			(end 0.7874 0.4064)
			(stroke
				(width 0.1524)
				(type default)
			)
			(layer "F.SilkS")
		)
		(fp_line
			(start 0.7874 0.4064)
			(end -0.7874 0.4064)
			(stroke
				(width 0.1524)
				(type default)
			)
			(layer "F.SilkS")
		)
		(fp_poly
			(pts
				(xy -0.508 0.2794) (xy -0.508 0.2286) (xy -0.635 0.2286) (xy -0.635 -0.254) (xy -0.5334 -0.254)
				(xy -0.5334 -0.2794) (xy 0.5334 -0.2794) (xy 0.5334 -0.254) (xy 0.635 -0.254) (xy 0.635 0.254) (xy 0.5334 0.254)
				(xy 0.5334 0.2794)
			)
			(stroke
				(width 0)
				(type default)
			)
			(fill no)
			(layer "F.CrtYd")
		)
		(pad "1" smd rect
			(at 0.40005 0)
			(size 0.4572 0.508)
			(layers "F.Cu" "F.Mask" "F.Paste")
			(net "PSU6_REMOTE_N")
		)
		(pad "2" smd rect
			(at -0.40005 0)
			(size 0.4572 0.508)
			(layers "F.Cu" "F.Mask" "F.Paste")
			(net "GND")
		)
	)
	(footprint ""
		(layer "F.Cu")
		(at 25.931622 -98.10369)
		(property "Reference" "R66"
			(at -4.080256 -0.075692 0)
			(unlocked yes)
			(layer "F.SilkS")
			(effects
				(font
					(size 0.7874 0.5842)
					(thickness 0.1524)
				)
				(justify left)
			)
		)
		(property "Value" ""
			(at 0 0 0)
			(layer "F.Fab")
			(effects
				(font
					(size 1.27 1.27)
				)
			)
		)
		(duplicate_pad_numbers_are_jumpers no)
		(fp_line
			(start -0.7874 -0.4064)
			(end 0.7874 -0.4064)
			(stroke
				(width 0.1524)
				(type default)
			)
			(layer "F.SilkS")
		)
		(fp_line
			(start -0.7874 0.4064)
			(end -0.7874 -0.4064)
			(stroke
				(width 0.1524)
				(type default)
			)
			(layer "F.SilkS")
		)
		(fp_line
			(start 0.7874 -0.4064)
			(end 0.7874 0.4064)
			(stroke
				(width 0.1524)
				(type default)
			)
			(layer "F.SilkS")
		)
		(fp_line
			(start 0.7874 0.4064)
			(end -0.7874 0.4064)
			(stroke
				(width 0.1524)
				(type default)
			)
			(layer "F.SilkS")
		)
		(fp_poly
			(pts
				(xy -0.508 0.2794) (xy -0.508 0.2286) (xy -0.635 0.2286) (xy -0.635 -0.254) (xy -0.5334 -0.254)
				(xy -0.5334 -0.2794) (xy 0.5334 -0.2794) (xy 0.5334 -0.254) (xy 0.635 -0.254) (xy 0.635 0.254) (xy 0.5334 0.254)
				(xy 0.5334 0.2794)
			)
			(stroke
				(width 0)
				(type default)
			)
			(fill no)
			(layer "F.CrtYd")
		)
		(pad "1" smd rect
			(at 0.40005 0)
			(size 0.4572 0.508)
			(layers "F.Cu" "F.Mask" "F.Paste")
			(net "PSU2_PS_KILL")
		)
		(pad "2" smd rect
			(at -0.40005 0)
			(size 0.4572 0.508)
			(layers "F.Cu" "F.Mask" "F.Paste")
			(net "P12V_STBY")
		)
	)
	(footprint ""
		(layer "F.Cu")
		(at 3.331464 -396.058136 180)
		(property "Reference" "R153"
			(at -1.305814 -0.218694 0)
			(unlocked yes)
			(layer "F.SilkS")
			(effects
				(font
					(size 0.7874 0.5842)
					(thickness 0.1524)
				)
				(justify left)
			)
		)
		(property "Value" ""
			(at 0 0 180)
			(layer "F.Fab")
			(effects
				(font
					(size 1.27 1.27)
				)
			)
		)
		(duplicate_pad_numbers_are_jumpers no)
		(fp_line
			(start 0.7874 0.4064)
			(end -0.7874 0.4064)
			(stroke
				(width 0.1524)
				(type default)
			)
			(layer "F.SilkS")
		)
		(fp_line
			(start 0.7874 -0.4064)
			(end 0.7874 0.4064)
			(stroke
				(width 0.1524)
				(type default)
			)
			(layer "F.SilkS")
		)
		(fp_line
			(start -0.7874 0.4064)
			(end -0.7874 -0.4064)
			(stroke
				(width 0.1524)
				(type default)
			)
			(layer "F.SilkS")
		)
		(fp_line
			(start -0.7874 -0.4064)
			(end 0.7874 -0.4064)
			(stroke
				(width 0.1524)
				(type default)
			)
			(layer "F.SilkS")
		)
		(fp_poly
			(pts
				(xy -0.508 0.2794) (xy -0.508 0.2286) (xy -0.635 0.2286) (xy -0.635 -0.254) (xy -0.5334 -0.254)
				(xy -0.5334 -0.2794) (xy 0.5334 -0.2794) (xy 0.5334 -0.254) (xy 0.635 -0.254) (xy 0.635 0.254) (xy 0.5334 0.254)
				(xy 0.5334 0.2794)
			)
			(stroke
				(width 0)
				(type default)
			)
			(fill no)
			(layer "F.CrtYd")
		)
		(pad "1" smd rect
			(at 0.40005 0 180)
			(size 0.4572 0.508)
			(layers "F.Cu" "F.Mask" "F.Paste")
			(net "GND")
		)
		(pad "2" smd rect
			(at -0.40005 0 180)
			(size 0.4572 0.508)
			(layers "F.Cu" "F.Mask" "F.Paste")
			(net "N42132358")
		)
	)
	(footprint ""
		(layer "F.Cu")
		(at 16.263366 -447.797428)
		(property "Reference" "C86"
			(at -1.061212 4.70662 0)
			(unlocked yes)
			(layer "F.SilkS")
			(effects
				(font
					(size 0.7874 0.5842)
					(thickness 0.1524)
				)
				(justify left)
			)
		)
		(property "Value" ""
			(at 0 0 0)
			(layer "F.Fab")
			(effects
				(font
					(size 1.27 1.27)
				)
			)
		)
		(duplicate_pad_numbers_are_jumpers no)
		(fp_line
			(start -1.905 -0.8636)
			(end 1.905 -0.8636)
			(stroke
				(width 0.1524)
				(type default)
			)
			(layer "F.SilkS")
		)
		(fp_line
			(start -1.905 0.8636)
			(end -1.905 -0.8636)
			(stroke
				(width 0.1524)
				(type default)
			)
			(layer "F.SilkS")
		)
		(fp_line
			(start 0 0.8382)
			(end 0 -0.8382)
			(stroke
				(width 0.1524)
				(type default)
			)
			(layer "F.SilkS")
		)
		(fp_line
			(start 1.905 -0.8636)
			(end 1.905 0.8636)
			(stroke
				(width 0.1524)
				(type default)
			)
			(layer "F.SilkS")
		)
		(fp_line
			(start 1.905 0.8636)
			(end -1.905 0.8636)
			(stroke
				(width 0.1524)
				(type default)
			)
			(layer "F.SilkS")
		)
		(fp_rect
			(start -1.524 0.7366)
			(end 1.524 -0.7366)
			(stroke
				(width 0)
				(type default)
			)
			(fill no)
			(layer "F.CrtYd")
		)
		(pad "1" smd rect
			(at 0.94996 0)
			(size 1.1176 1.3716)
			(layers "F.Cu" "F.Mask" "F.Paste")
			(net "P12V")
		)
		(pad "2" smd rect
			(at -0.94996 0)
			(size 1.1176 1.3716)
			(layers "F.Cu" "F.Mask" "F.Paste")
			(net "GND")
		)
	)
	(footprint ""
		(layer "F.Cu")
		(at 74.798682 -19.257772 -90)
		(property "Reference" "C1"
			(at -2.757424 -0.074422 90)
			(unlocked yes)
			(layer "F.SilkS")
			(effects
				(font
					(size 0.7874 0.5842)
					(thickness 0.1524)
				)
			)
		)
		(property "Value" ""
			(at 0 0 270)
			(layer "F.Fab")
			(effects
				(font
					(size 1.27 1.27)
				)
			)
		)
		(duplicate_pad_numbers_are_jumpers no)
		(fp_line
			(start -1.2954 0.5842)
			(end -1.2954 -0.5842)
			(stroke
				(width 0.1524)
				(type default)
			)
			(layer "F.SilkS")
		)
		(fp_line
			(start 1.2954 0.5842)
			(end -1.2954 0.5842)
			(stroke
				(width 0.1524)
				(type default)
			)
			(layer "F.SilkS")
		)
		(fp_line
			(start -1.2954 -0.5842)
			(end 1.2954 -0.5842)
			(stroke
				(width 0.1524)
				(type default)
			)
			(layer "F.SilkS")
		)
		(fp_line
			(start 0 -0.5842)
			(end 0 0.5842)
			(stroke
				(width 0.1524)
				(type default)
			)
			(layer "F.SilkS")
		)
		(fp_line
			(start 1.2954 -0.5842)
			(end 1.2954 0.5842)
			(stroke
				(width 0.1524)
				(type default)
			)
			(layer "F.SilkS")
		)
		(fp_poly
			(pts
				(xy 0.8636 -0.4572) (xy 0.8636 -0.3556) (xy 1.143 -0.3556) (xy 1.143 0.3556) (xy 0.8636 0.3556)
				(xy 0.8636 0.4572) (xy -0.8636 0.4572) (xy -0.8636 0.3556) (xy -1.143 0.3556) (xy -1.143 -0.3556)
				(xy -0.8636 -0.3556) (xy -0.8636 -0.4572)
			)
			(stroke
				(width 0)
				(type default)
			)
			(fill no)
			(layer "F.CrtYd")
		)
		(fp_line
			(start -0.884936 0.504952)
			(end -0.884936 -0.504952)
			(stroke
				(width 0.1)
				(type default)
			)
			(layer "F.Fab")
		)
		(fp_line
			(start 0.884936 0.504952)
			(end -0.884936 0.504952)
			(stroke
				(width 0.1)
				(type default)
			)
			(layer "F.Fab")
		)
		(fp_line
			(start -0.884936 -0.504952)
			(end 0.884936 -0.504952)
			(stroke
				(width 0.1)
				(type default)
			)
			(layer "F.Fab")
		)
		(fp_line
			(start 0.884936 -0.504952)
			(end 0.884936 0.504952)
			(stroke
				(width 0.1)
				(type default)
			)
			(layer "F.Fab")
		)
		(pad "1" smd rect
			(at 0.7366 0)
			(size 0.7112 0.8128)
			(layers "F.Cu" "F.Mask" "F.Paste")
			(net "P12V")
		)
		(pad "2" smd rect
			(at -0.7366 0)
			(size 0.7112 0.8128)
			(layers "F.Cu" "F.Mask" "F.Paste")
			(net "GND")
		)
	)
	(footprint ""
		(layer "F.Cu")
		(at 39.934642 -374.14708)
		(property "Reference" "R44"
			(at 2.011172 0.405638 0)
			(unlocked yes)
			(layer "F.SilkS")
			(effects
				(font
					(size 0.7874 0.5842)
					(thickness 0.1524)
				)
				(justify left)
			)
		)
		(property "Value" ""
			(at 0 0 0)
			(layer "F.Fab")
			(effects
				(font
					(size 1.27 1.27)
				)
			)
		)
		(duplicate_pad_numbers_are_jumpers no)
		(fp_line
			(start -0.7874 -0.4064)
			(end 0.7874 -0.4064)
			(stroke
				(width 0.1524)
				(type default)
			)
			(layer "F.SilkS")
		)
		(fp_line
			(start -0.7874 0.4064)
			(end -0.7874 -0.4064)
			(stroke
				(width 0.1524)
				(type default)
			)
			(layer "F.SilkS")
		)
		(fp_line
			(start 0.7874 -0.4064)
			(end 0.7874 0.4064)
			(stroke
				(width 0.1524)
				(type default)
			)
			(layer "F.SilkS")
		)
		(fp_line
			(start 0.7874 0.4064)
			(end -0.7874 0.4064)
			(stroke
				(width 0.1524)
				(type default)
			)
			(layer "F.SilkS")
		)
		(fp_poly
			(pts
				(xy -0.508 0.2794) (xy -0.508 0.2286) (xy -0.635 0.2286) (xy -0.635 -0.254) (xy -0.5334 -0.254)
				(xy -0.5334 -0.2794) (xy 0.5334 -0.2794) (xy 0.5334 -0.254) (xy 0.635 -0.254) (xy 0.635 0.254) (xy 0.5334 0.254)
				(xy 0.5334 0.2794)
			)
			(stroke
				(width 0)
				(type default)
			)
			(fill no)
			(layer "F.CrtYd")
		)
		(pad "1" smd rect
			(at 0.40005 0)
			(size 0.4572 0.508)
			(layers "F.Cu" "F.Mask" "F.Paste")
			(net "GND")
		)
		(pad "2" smd rect
			(at -0.40005 0)
			(size 0.4572 0.508)
			(layers "F.Cu" "F.Mask" "F.Paste")
			(net "P12V_STBY")
		)
	)
	(footprint ""
		(layer "F.Cu")
		(at 50.418238 -439.763154 180)
		(property "Reference" "CE20"
			(at -4.84124 2.782824 0)
			(unlocked yes)
			(layer "F.SilkS")
			(effects
				(font
					(size 0.7874 0.5842)
					(thickness 0.1524)
				)
				(justify left)
			)
		)
		(property "Value" ""
			(at 0 0 180)
			(layer "F.Fab")
			(effects
				(font
					(size 1.27 1.27)
				)
			)
		)
		(duplicate_pad_numbers_are_jumpers no)
		(fp_line
			(start 0 -4.2672)
			(end 0 4.2672)
			(stroke
				(width 0.1524)
				(type default)
			)
			(layer "F.SilkS")
		)
		(fp_circle
			(center 0 0)
			(end -4.2672 0)
			(stroke
				(width 0.1524)
				(type default)
			)
			(fill no)
			(layer "F.SilkS")
		)
		(fp_poly
			(pts
				(arc
					(start 0 -4.2672)
					(mid 4.2672 0)
					(end 0 4.2672)
				)
			)
			(stroke
				(width 0)
				(type default)
			)
			(fill yes)
			(layer "F.SilkS")
		)
		(fp_poly
			(pts
				(xy -2.5146 -0.762) (xy -0.9906 -0.762) (xy -0.9906 0.762) (xy -2.5146 0.762)
			)
			(stroke
				(width 0)
				(type default)
			)
			(fill no)
			(layer "B.CrtYd")
		)
		(fp_poly
			(pts
				(arc
					(start 1.7526 0.762)
					(mid 2.291415 -0.538815)
					(end 0.9906 0)
				)
				(arc
					(start 0.9906 0.0254)
					(mid 1.206345 0.546255)
					(end 1.7272 0.762)
				)
			)
			(stroke
				(width 0)
				(type default)
			)
			(fill no)
			(layer "B.CrtYd")
		)
		(fp_poly
			(pts
				(arc
					(start -4.2672 0)
					(mid 4.2672 0)
					(end -4.2672 0)
				)
			)
			(stroke
				(width 0)
				(type default)
			)
			(fill no)
			(layer "F.CrtYd")
		)
		(fp_circle
			(center 0 0)
			(end -4.2672 0)
			(stroke
				(width 0.1)
				(type default)
			)
			(fill no)
			(layer "F.Fab")
		)
		(fp_text user "+"
			(at -5.6642 -0.34925 180)
			(unlocked yes)
			(layer "F.SilkS")
			(effects
				(font
					(size 1.905 1.4224)
					(thickness 0.1524)
				)
				(justify left)
			)
		)
		(fp_text user "+"
			(at -5.6642 -0.34925 180)
			(unlocked yes)
			(layer "F.Fab")
			(effects
				(font
					(size 1.905 1.4224)
					(thickness 0.000001)
				)
				(justify left)
			)
		)
		(pad "1" thru_hole rect
			(at -1.75006 0 180)
			(size 1.397 1.397)
			(drill 0.9144)
			(layers "*.Cu" "*.Mask")
			(remove_unused_layers no)
			(net "P12V")
			(clearance 0.0127)
			(thermal_gap 0.0127)
			(padstack
				(mode front_inner_back)
				(layer "Inner"
					(shape circle)
					(size 1.397 1.397)
					(clearance 0.0127)
				)
				(layer "B.Cu"
					(shape rect)
					(size 1.397 1.397)
					(clearance 0.0127)
				)
			)
		)
		(pad "2" thru_hole circle
			(at 1.75006 0 180)
			(size 1.397 1.397)
			(drill 0.9144)
			(layers "*.Cu" "*.Mask")
			(remove_unused_layers no)
			(net "GND")
			(clearance 0.0127)
			(thermal_gap 0.0127)
		)
	)
	(footprint ""
		(layer "F.Cu")
		(at 71.405496 -259.450078 90)
		(property "Reference" "C49"
			(at -4.355846 -0.127762 90)
			(unlocked yes)
			(layer "F.SilkS")
			(effects
				(font
					(size 0.7874 0.5842)
					(thickness 0.1524)
				)
				(justify left)
			)
		)
		(property "Value" ""
			(at 0 0 90)
			(layer "F.Fab")
			(effects
				(font
					(size 1.27 1.27)
				)
			)
		)
		(duplicate_pad_numbers_are_jumpers no)
		(fp_line
			(start 0.7874 -0.4064)
			(end 0.7874 0.4064)
			(stroke
				(width 0.1524)
				(type default)
			)
			(layer "F.SilkS")
		)
		(fp_line
			(start -0.7874 -0.4064)
			(end 0.7874 -0.4064)
			(stroke
				(width 0.1524)
				(type default)
			)
			(layer "F.SilkS")
		)
		(fp_line
			(start 0 0.381)
			(end 0 -0.381)
			(stroke
				(width 0.1524)
				(type default)
			)
			(layer "F.SilkS")
		)
		(fp_line
			(start 0.7874 0.4064)
			(end -0.7874 0.4064)
			(stroke
				(width 0.1524)
				(type default)
			)
			(layer "F.SilkS")
		)
		(fp_line
			(start -0.7874 0.4064)
			(end -0.7874 -0.4064)
			(stroke
				(width 0.1524)
				(type default)
			)
			(layer "F.SilkS")
		)
		(fp_poly
			(pts
				(xy -0.5334 0.254) (xy -0.635 0.254) (xy -0.635 0.2286) (xy -0.635 -0.254) (xy -0.5334 -0.254) (xy -0.5334 -0.2794)
				(xy 0.5334 -0.2794) (xy 0.5334 -0.254) (xy 0.635 -0.254) (xy 0.635 0.254) (xy 0.5334 0.254) (xy 0.5334 0.2794)
				(xy -0.508 0.2794) (xy -0.5334 0.2794)
			)
			(stroke
				(width 0)
				(type default)
			)
			(fill no)
			(layer "F.CrtYd")
		)
		(pad "1" smd rect
			(at 0.40005 0 90)
			(size 0.4572 0.508)
			(layers "F.Cu" "F.Mask" "F.Paste")
			(net "P12V")
		)
		(pad "2" smd rect
			(at -0.40005 0 90)
			(size 0.4572 0.508)
			(layers "F.Cu" "F.Mask" "F.Paste")
			(net "GND")
		)
	)
)
